# S9S_MB_2U (Grand Teton) — schematic netlist excerpt (pin names and nets, part order shuffled) for the footprints in the layout excerpt that follows; sources: Cadence DE-HDL packaged netlist, KiCad conversion of 03242023_DA0F0TMBIJ0_F0T_Motherboard_J_brd_V01_OCP.brd

R3500  Q_RES  4.7K 5% CHIP  pkg 0402LF  page 238 : A = P3V3_OCP_SFF ; B = SMB_OCP_SFF_3V3AUX_BUF_SCL
C1820  Q_CAP  0.1UF 25V 10% X7R  pkg 0402  page 164 : A = P3V3_AUX ; B = GND

(kicad_pcb
	(version 20260206)
	(generator "pcbnew")
	(generator_version "10.0")
	(general
		(thickness 1.6)
		(legacy_teardrops no)
	)
	(paper "A4")
	(title_block
		(title "03242023_DA0F0TMBIJ0_F0T_Motherboard_J_brd_V01_OCP.brd")
		(comment 1 "Grand Teton / footprints 3617-3618 of 6105")
	)
	(layers
		(0 "F.Cu" signal "TOP")
		(4 "In1.Cu" signal "GND")
		(6 "In2.Cu" signal "IN1")
		(8 "In3.Cu" signal "GND1")
		(10 "In4.Cu" signal "IN2")
		(12 "In5.Cu" signal "GND2")
		(14 "In6.Cu" signal "IN3")
		(16 "In7.Cu" signal "GND3")
		(18 "In8.Cu" signal "VCC")
		(20 "In9.Cu" signal "VCC1")
		(22 "In10.Cu" signal "GND4")
		(24 "In11.Cu" signal "IN4")
		(26 "In12.Cu" signal "GND5")
		(28 "In13.Cu" signal "IN5")
		(30 "In14.Cu" signal "GND6")
		(32 "In15.Cu" signal "IN6")
		(34 "In16.Cu" signal "GND7")
		(2 "B.Cu" signal "BOTTOM")
		(9 "F.Adhes" user "F.Adhesive")
		(11 "B.Adhes" user "B.Adhesive")
		(13 "F.Paste" user "Package Geometry/Pastemask Top")
		(15 "B.Paste" user "Package Geometry/Pastemask Bottom")
		(5 "F.SilkS" user "Ref Des/Silkscreen Top")
		(7 "B.SilkS" user "Ref Des/Silkscreen Bottom")
		(1 "F.Mask" user "Board Geometry/Soldermask Top")
		(3 "B.Mask" user "Board Geometry/Soldermask Bottom")
		(17 "Dwgs.User" user "User.Drawings")
		(19 "Cmts.User" user "User.Comments")
		(21 "Eco1.User" user "User.Eco1")
		(23 "Eco2.User" user "User.Eco2")
		(25 "Edge.Cuts" user "Board Geometry/Outline")
		(27 "Margin" user)
		(31 "F.CrtYd" user "Package Geometry/Place Bound Top")
		(29 "B.CrtYd" user "Package Geometry/Place Bound Bottom")
		(35 "F.Fab" user "Ref Des/Assembly Top")
		(33 "B.Fab" user "Ref Des/Assembly Bottom")
	)
	(footprint ""
		(layer "F.Cu")
		(at 450.43725 -45.314362 180)
		(property "Reference" "R3500"
			(at 0 0 180)
			(layer "F.SilkS")
			(hide yes)
			(effects
				(font
					(size 1.27 1.27)
				)
			)
		)
		(property "Value" ""
			(at 0 0 180)
			(layer "F.Fab")
			(effects
				(font
					(size 1.27 1.27)
				)
			)
		)
		(duplicate_pad_numbers_are_jumpers no)
		(fp_line
			(start 0.7874 0.4064)
			(end -0.7874 0.4064)
			(stroke
				(width 0.1524)
				(type default)
			)
			(layer "F.SilkS")
		)
		(fp_line
			(start 0.7874 -0.4064)
			(end 0.7874 0.4064)
			(stroke
				(width 0.1524)
				(type default)
			)
			(layer "F.SilkS")
		)
		(fp_line
			(start -0.7874 0.4064)
			(end -0.7874 -0.4064)
			(stroke
				(width 0.1524)
				(type default)
			)
			(layer "F.SilkS")
		)
		(fp_line
			(start -0.7874 -0.4064)
			(end 0.7874 -0.4064)
			(stroke
				(width 0.1524)
				(type default)
			)
			(layer "F.SilkS")
		)
		(fp_line
			(start 0.67945 0.3048)
			(end 0.120396 0.3048)
			(stroke
				(width 0.1)
				(type default)
			)
			(layer "F.Fab")
		)
		(fp_line
			(start 0.67945 -0.3048)
			(end 0.67945 0.3048)
			(stroke
				(width 0.1)
				(type default)
			)
			(layer "F.Fab")
		)
		(fp_line
			(start 0.12065 -0.2794)
			(end 0.12065 -0.3048)
			(stroke
				(width 0.1)
				(type default)
			)
			(layer "F.Fab")
		)
		(fp_line
			(start 0.12065 -0.3048)
			(end 0.67945 -0.3048)
			(stroke
				(width 0.1)
				(type default)
			)
			(layer "F.Fab")
		)
		(fp_line
			(start 0.120396 0.3048)
			(end 0.120396 0.2794)
			(stroke
				(width 0.1)
				(type default)
			)
			(layer "F.Fab")
		)
		(fp_line
			(start 0.120396 0.2794)
			(end -0.12065 0.2794)
			(stroke
				(width 0.1)
				(type default)
			)
			(layer "F.Fab")
		)
		(fp_line
			(start -0.12065 0.3048)
			(end -0.67945 0.3048)
			(stroke
				(width 0.1)
				(type default)
			)
			(layer "F.Fab")
		)
		(fp_line
			(start -0.12065 0.2794)
			(end -0.12065 0.3048)
			(stroke
				(width 0.1)
				(type default)
			)
			(layer "F.Fab")
		)
		(fp_line
			(start -0.12065 -0.2794)
			(end 0.12065 -0.2794)
			(stroke
				(width 0.1)
				(type default)
			)
			(layer "F.Fab")
		)
		(fp_line
			(start -0.12065 -0.305054)
			(end -0.12065 -0.2794)
			(stroke
				(width 0.1)
				(type default)
			)
			(layer "F.Fab")
		)
		(fp_line
			(start -0.67945 0.3048)
			(end -0.67945 -0.305054)
			(stroke
				(width 0.1)
				(type default)
			)
			(layer "F.Fab")
		)
		(fp_line
			(start -0.67945 -0.305054)
			(end -0.12065 -0.305054)
			(stroke
				(width 0.1)
				(type default)
			)
			(layer "F.Fab")
		)
		(pad "1" smd circle
			(at -0.40005 0 180)
			(size 0 0)
			(layers "F.Cu" "F.Mask" "F.Paste")
			(net "P3V3_OCP_SFF")
		)
		(pad "2" smd circle
			(at 0.40005 0 180)
			(size 0 0)
			(layers "F.Cu" "F.Mask" "F.Paste")
			(net "SMB_OCP_SFF_3V3AUX_BUF_SCL")
		)
	)
	(footprint ""
		(layer "F.Cu")
		(at 92.7354 -39.675308)
		(property "Reference" "C1820"
			(at 0 0 0)
			(layer "F.SilkS")
			(hide yes)
			(effects
				(font
					(size 1.27 1.27)
				)
			)
		)
		(property "Value" ""
			(at 0 0 0)
			(layer "F.Fab")
			(effects
				(font
					(size 1.27 1.27)
				)
			)
		)
		(duplicate_pad_numbers_are_jumpers no)
		(fp_line
			(start -0.7874 -0.4064)
			(end 0.7874 -0.4064)
			(stroke
				(width 0.1524)
				(type default)
			)
			(layer "F.SilkS")
		)
		(fp_line
			(start -0.7874 0.4064)
			(end -0.7874 -0.4064)
			(stroke
				(width 0.1524)
				(type default)
			)
			(layer "F.SilkS")
		)
		(fp_line
			(start 0.7874 -0.4064)
			(end 0.7874 0.4064)
			(stroke
				(width 0.1524)
				(type default)
			)
			(layer "F.SilkS")
		)
		(fp_line
			(start 0.7874 0.4064)
			(end -0.7874 0.4064)
			(stroke
				(width 0.1524)
				(type default)
			)
			(layer "F.SilkS")
		)
		(fp_line
			(start -0.67945 -0.305054)
			(end -0.12065 -0.305054)
			(stroke
				(width 0.1)
				(type default)
			)
			(layer "F.Fab")
		)
		(fp_line
			(start -0.67945 0.3048)
			(end -0.67945 -0.305054)
			(stroke
				(width 0.1)
				(type default)
			)
			(layer "F.Fab")
		)
		(fp_line
			(start -0.12065 -0.305054)
			(end -0.12065 -0.2794)
			(stroke
				(width 0.1)
				(type default)
			)
			(layer "F.Fab")
		)
		(fp_line
			(start -0.12065 -0.2794)
			(end 0.12065 -0.2794)
			(stroke
				(width 0.1)
				(type default)
			)
			(layer "F.Fab")
		)
		(fp_line
			(start -0.12065 0.2794)
			(end -0.12065 0.3048)
			(stroke
				(width 0.1)
				(type default)
			)
			(layer "F.Fab")
		)
		(fp_line
			(start -0.12065 0.3048)
			(end -0.67945 0.3048)
			(stroke
				(width 0.1)
				(type default)
			)
			(layer "F.Fab")
		)
		(fp_line
			(start 0.120396 0.2794)
			(end -0.12065 0.2794)
			(stroke
				(width 0.1)
				(type default)
			)
			(layer "F.Fab")
		)
		(fp_line
			(start 0.120396 0.3048)
			(end 0.120396 0.2794)
			(stroke
				(width 0.1)
				(type default)
			)
			(layer "F.Fab")
		)
		(fp_line
			(start 0.12065 -0.3048)
			(end 0.67945 -0.3048)
			(stroke
				(width 0.1)
				(type default)
			)
			(layer "F.Fab")
		)
		(fp_line
			(start 0.12065 -0.2794)
			(end 0.12065 -0.3048)
			(stroke
				(width 0.1)
				(type default)
			)
			(layer "F.Fab")
		)
		(fp_line
			(start 0.67945 -0.3048)
			(end 0.67945 0.3048)
			(stroke
				(width 0.1)
				(type default)
			)
			(layer "F.Fab")
		)
		(fp_line
			(start 0.67945 0.3048)
			(end 0.120396 0.3048)
			(stroke
				(width 0.1)
				(type default)
			)
			(layer "F.Fab")
		)
		(pad "1" smd circle
			(at -0.40005 0)
			(size 0 0)
			(layers "F.Cu" "F.Mask" "F.Paste")
			(net "P3V3_AUX")
		)
		(pad "2" smd circle
			(at 0.40005 0)
			(size 0 0)
			(layers "F.Cu" "F.Mask" "F.Paste")
			(net "GND")
		)
	)
)
